#ISCELL
  mstr_misc dns *
  *
#ISCELL
  pure_quanta quanta_title_block_c *
  *
#ISCELL
  logical_power universal_power *
  page25_i135
#ISCELL
  standard offpage *
  page25_i137
#CELL
  pure_quanta 74lvc1g74dp *
  page25_i138
#ISCELL
  standard offpage *
  page25_i139
#ISCELL
  standard offpage *
  page25_i140
#CELL
  pure_quanta q_res *
  page25_i142
#CELL
  pure_quanta q_res *
  page25_i143
#ISCELL
  logical_power universal_gnd *
  page25_i144
#ISCELL
  logical_power universal_power *
  page25_i145
#CELL
  pure_quanta q_cap *
  page25_i146
#ISCELL
  logical_power universal_gnd *
  page25_i147
#CELL
  pure_quanta q_res *
  page25_i149
#CELL
  pure_quanta sn74lvc1g14dckr *
  page25_i150
#ISCELL
  standard offpage *
  page25_i152
#ISCELL
  logical_power universal_power *
  page25_i153
#CELL
  pure_quanta q_cap *
  page25_i154
#ISCELL
  logical_power universal_gnd *
  page25_i155
#CELL
  pure_quanta q_res *
  page25_i156
#ISCELL
  logical_power universal_gnd *
  page25_i157
#ISCELL
  logical_power universal_gnd *
  page25_i158
#ISCELL
  standard offpage *
  page25_i162
#ISCELL
  standard offpage *
  page25_i163
#ISCELL
  logical_power universal_power *
  page25_i166
#CELL
  pure_quanta sconn3_212h9103gbr1 *
  page25_i169
#CELL
  pure_quanta q_res *
  page25_i170
#CELL
  pure_quanta q_res *
  page25_i171
#CELL
  pure_quanta q_res *
  page25_i172
#CELL
  pure_quanta q_res *
  page25_i173
#CELL
  pure_quanta q_res *
  page25_i174
#CELL
  pure_quanta q_res *
  page25_i175
#CELL
  pure_quanta q_res *
  page25_i176
#ISCELL
  logical_power universal_power *
  page25_i2
#CELL
  pure_quanta q_res *
  page25_i3
#CELL
  pure_quanta sn74lvc1g07dckr *
  page25_i61
#ISCELL
  logical_power universal_gnd *
  page25_i62
#ISCELL
  logical_power universal_gnd *
  page25_i64
#CELL
  pure_quanta q_cap *
  page25_i65
#CELL
  pure_quanta q_res *
  page25_i67
#ISCELL
  standard offpage *
  page25_i70
#ISCELL
  standard offpage *
  page25_i71
#ISCELL
  logical_power universal_power *
  page25_i72
#CELL
  pure_quanta q_res *
  page25_i73
